pagename "INTEL_CORP_BPAGE"
version 1
lowerleft (-8000, 0)
upperright (0, 5000)
xmark "1" -1000
xmark "2" -3000
xmark "3" -5000
xmark "4" -7000
ymark "A" 1250
ymark "B" 3750
excludearea "1" (-8000,0) (0,400)
{schrep "basenets" (1,20)(2,35)(3,25)}
schrep "basenets" (1,20)(2,21)
{schrep "netsbypage" (1,7)(2,15)(3,20)(4,15)(5,21)}
schrep "netsbypage" (1,5)(2,20)(5,21)
schrep "synonyms" (1,15)(2,20)(3,25)(4,21)
{schrep "crefparts" (1,10)(2,20)(3,50)}
schrep "crefparts" (1,7)(2,20)(3,20)

pagename "INTEL_CORP_BPAGE"
version 2
lowerleft (-8000, 0)
upperright (0, 5000)
xmark "1" -1000
xmark "2" -3000
xmark "3" -5000
xmark "4" -7000
ymark "A" 1250
ymark "B" 3750
excludearea "1" (-3000,0) (0,1000)
excludearea "2" (-3750,4550) (0,5000)
{schrep "basenets" (1,20)(2,35)(3,25)}
schrep "basenets" (1,20)(2,21)
{schrep "netsbypage" (1,7)(2,15)(3,20)(4,15)(5,21)}
schrep "netsbypage" (1,5)(2,20)(5,21)
schrep "synonyms" (1,15)(2,20)(3,25)(4,21)
{schrep "crefparts" (1,10)(2,20)(3,50)}
schrep "crefparts" (1,7)(2,20)(3,20)

pagename "INTEL_CORP_BPAGE"
version 3
lowerleft (-8000, 0)
upperright (0, 5000)
xmark "1" -1000
xmark "2" -3000
xmark "3" -5000
xmark "4" -7000
ymark "A" 1250
ymark "B" 3750
excludearea "1" (-3000,0) (0,1000)
excludearea "2" (-3750,4550) (0,5000)
{schrep "basenets" (1,20)(2,35)(3,25)}
schrep "basenets" (1,20)(2,21)
{schrep "netsbypage" (1,7)(2,15)(3,20)(4,15)(5,21)}
schrep "netsbypage" (1,5)(2,20)(5,21)
schrep "synonyms" (1,15)(2,20)(3,25)(4,21)
{schrep "crefparts" (1,10)(2,20)(3,50)}
schrep "crefparts" (1,7)(2,20)(3,20)

pagename "APD_OR_SCH"
version 1
lowerleft (-8000, 200)
upperright (0, 5000)
xmark "1" -500
xmark "2" -1500
xmark "3" -2500
xmark "4" -3500
xmark "5" -4500
xmark "6" -5500
xmark "7" -6500
xmark "8" -7500
ymark "A" 1000
ymark "B" 2200
ymark "C" 3300
ymark "D" 4500
{schrep "basenets" (1,20)(2,35)(3,25)}
schrep "basenets" (1,20)(3,25)
schrep "netsbypage" (1,7)(2,15)(3,20)(4,15)(5,21)
schrep "synonyms" (1,15)(2,20)(3,25)(4,21)
{schrep "crefparts" (1,10)(2,20)(3,50)}
schrep "crefparts" (1,10)(2,20)(3,20)

pagename "APD_SC_SCH"
version 1
lowerleft (-8000, 200)
upperright (0, 5000)
xmark "1" -460
xmark "2" -1485
xmark "3" -2485
xmark "4" -3485
xmark "5" -4512
xmark "6" -5512
xmark "7" -6512
xmark "8" -7485
ymark "A" 990
ymark "B" 2195
ymark "C" 3317
ymark "D" 4438
{schrep "basenets" (1,20)(2,35)(3,25)}
schrep "basenets" (1,20)(3,25)
schrep "netsbypage" (1,7)(2,15)(3,20)(4,15)(5,21)
schrep "synonyms" (1,15)(2,20)(3,25)(4,21)
{schrep "crefparts" (1,10)(2,20)(3,50)}
schrep "crefparts" (1,10)(2,20)(3,20)

pagename "A SIZE PAGE"
version 1
lowerleft (-3750, 0)
upperright (0, 5000)
xmark "1" -500
xmark "2" -1500
xmark "3" -2500
xmark "4" -3425
ymark "A" 950
ymark "B" 2200
ymark "C" 3350
ymark "D" 4475
excludearea "1" (-1700,0) (0,400)
pagename "B SIZE PAGE"
version 1
lowerleft (-8000, 0)
upperright (0, 5000)
xmark "1" -500
xmark "2" -1500
xmark "3" -2500
xmark "4" -3500
xmark "5" -4500
xmark "6" -5500
xmark "7" -6500
xmark "8" -7500
ymark "A" 1000
ymark "B" 2200
ymark "C" 3350
ymark "D" 4500
excludearea "1" (-2550,0) (0,400)
pagename "C SIZE PAGE"
version 1
lowerleft (-10650, 100)
upperright (-75, 8175)
xmark "1" -750
xmark "2" -2000
xmark "3" -3350
xmark "4" -4700
xmark "5" -6050
xmark "6" -7400
xmark "7" -8750
xmark "8" -10100
ymark "A" 675
ymark "B" 2025
ymark "C" 3375
ymark "D" 4750
ymark "E" 6075
ymark "F" 7525
excludearea "1" (-4050,100) (-75,900)
excludearea "2" (-2850,7800) (-75,8175)
pagename "D SIZE PAGE"
version 1
lowerleft (-14625, 250)
upperright (1875, 10750)
xmark "1" 950
xmark "2" -1075
xmark "3" -3200
xmark "4" -5300
xmark "5" -7450
xmark "6" -9575
xmark "7" -11700
xmark "8" -13725
ymark "A" 1625
ymark "B" 4200
ymark "C" 6825
ymark "D" 9475
excludearea "1" (-2250,250) (1875,1100)
excludearea "2" (-1600,10150) (1875,10750)
pagename "E SIZE PAGE"
version 1
lowerleft (-10700, -8200)
upperright (10750, 7750)
xmark "1" 9600
xmark "2" 6850
xmark "3" 4150
xmark "4" 1400
xmark "5" -1350
xmark "6" -4125
xmark "7" -6875
xmark "8" -9650
ymark "A" -7700
ymark "B" -5500
ymark "C" -3450
ymark "D" -1300
ymark "E" 800
ymark "F" 2950
ymark "G" 5100
ymark "H" 7150
excludearea "1" (6800,-8200) (10750,-7350)
excludearea "2" (6900,7400) (10750,7750)
pagename "F SIZE PAGE"
version 1
lowerleft (-9725, -6725)
upperright (9750, 6725)
xmark "1" 8825
xmark "2" 6250
xmark "3" 3750
xmark "4" 1250
xmark "5" -1300
xmark "6" -3750
xmark "7" -6200
xmark "8" -8800
ymark "A" -5800
ymark "B" -3400
ymark "C" -1050
ymark "D" 1250
ymark "E" 3575
ymark "F" 5800
excludearea "1" (5700,-6725) (9750,-5800)
excludearea "2" (5900,6350) (9750,6725)
pagename "CADENCE A SIZE PAGE"
version 1
lowerleft (-3750, 0)
upperright (0, 5000)
xmark "1" -500
xmark "2" -1500
xmark "3" -2500
xmark "4" -3425
ymark "A" 950
ymark "B" 2200
ymark "C" 3350
ymark "D" 4475
excludearea "1" (-3750,0) (0,450)
pagename "CADENCE A SIZE PAGE"
version 2
lowerleft (-3750, 0)
upperright (0, 5000)
xmark "1" -500
xmark "2" -1500
xmark "3" -2500
xmark "4" -3425
ymark "A" 950
ymark "B" 2200
ymark "C" 3350
ymark "D" 4475
excludearea "1" (-3750,0) (0,450)
pagename "CADENCE B SIZE PAGE"
version 1
lowerleft (-8000, 0)
upperright (0, 5000)
xmark "1" -500
xmark "2" -1500
xmark "3" -2500
xmark "4" -3500
xmark "5" -4500
xmark "6" -5500
xmark "7" -6500
xmark "8" -7500
ymark "A" 1000
ymark "B" 2200
ymark "C" 3350
ymark "D" 4500
excludearea "1" (-8000,0) (0,400)
pagename "CADENCE B SIZE PAGE"
version 2
lowerleft (-8000, 0)
upperright (0, 5000)
xmark "1" -500
xmark "2" -1500
xmark "3" -2500
xmark "4" -3500
xmark "5" -4500
xmark "6" -5500
xmark "7" -6500
xmark "8" -7500
ymark "A" 1000
ymark "B" 2200
ymark "C" 3350
ymark "D" 4500
excludearea "1" (-8000,0) (0,400)
pagename "CADENCE B SIZE PAGE"
version 3
lowerleft (-8000, 0)
upperright (0, 5000)
xmark "1" -500
xmark "2" -1500
xmark "3" -2500
xmark "4" -3500
xmark "5" -4500
xmark "6" -5500
xmark "7" -6500
xmark "8" -7500
ymark "A" 1000
ymark "B" 2200
ymark "C" 3350
ymark "D" 4500
excludearea "1" (-8000,0) (0,1600)
excludearea "2" (-3050,4600) (0,5000)
pagename "VALID A SIZE PAGE"
version 1
lowerleft (-3750, 0)
upperright (0, 5000)
xmark "1" -500
xmark "2" -1500
xmark "3" -2500
xmark "4" -3425
ymark "A" 950
ymark "B" 2200
ymark "C" 3350
ymark "D" 4475
excludearea "1" (-3750,0) (0,400)
pagename "VALID A SIZE PAGE"
version 2
lowerleft (-3750, 0)
upperright (0, 5000)
xmark "1" -500
xmark "2" -1500
xmark "3" -2500
xmark "4" -3425
ymark "A" 950
ymark "B" 2200
ymark "C" 3350
ymark "D" 4475
excludearea "1" (-3750,0) (0,400)
pagename "VALID B SIZE PAGE"
version 1
lowerleft (-8000, 0)
upperright (0, 5000)
xmark "1" -500
xmark "2" -1500
xmark "3" -2500
xmark "4" -3500
xmark "5" -4500
xmark "6" -5500
xmark "7" -6500
xmark "8" -7500
ymark "A" 1000
ymark "B" 2200
ymark "C" 3350
ymark "D" 4500
excludearea "1" (-8000,0) (0,400)
pagename "VALID B SIZE PAGE"
version 2
lowerleft (-8000, 0)
upperright (0, 5000)
xmark "1" -500
xmark "2" -1500
xmark "3" -2500
xmark "4" -3500
xmark "5" -4500
xmark "6" -5500
xmark "7" -6500
xmark "8" -7500
ymark "A" 1000
ymark "B" 2200
ymark "C" 3350
ymark "D" 4500
excludearea "1" (-8000,0) (0,400)
pagename "VALID B SIZE PAGE"
version 3
lowerleft (-8000, 0)
upperright (0, 5000)
xmark "1" -500
xmark "2" -1500
xmark "3" -2500
xmark "4" -3500
xmark "5" -4500
xmark "6" -5500
xmark "7" -6500
xmark "8" -7500
ymark "A" 1000
ymark "B" 2200
ymark "C" 3350
ymark "D" 4500
excludearea "1" (-8000,0) (0,1600)
excludearea "2" (-3050,4600) (0,5000)
pagename "BPAGE"
version 1
lowerleft(-7800,225)
upperright(-125,4825)
xmark "8" -7500
xmark "7" -6500
xmark "6" -5500
xmark "5" -4500
xmark "4" -3500
xmark "3" -2500
xmark "2" -1500
xmark "1" -500
ymark "A" 975
ymark "B" 2175
ymark "C" 3300
ymark "D" 4475
{schrep "basenets" (1,20)(2,35)(3,25)}
schrep "basenets" (1,20)(3,25)
schrep "netsbypage" (1,7)(2,15)(3,20)(4,15)(5,21)
schrep "synonyms" (1,15)(2,20)(3,25)(4,21)
{schrep "crefparts" (1,10)(2,20)(3,50)}
schrep "crefparts" (1,10)(2,20)(3,20)

pagename "BPAGE_APD"
lowerleft(-7800,225)
upperright(-125,4825)
xmark "8" -7500
xmark "7" -6500
xmark "6" -5500
xmark "5" -4500
xmark "4" -3500
xmark "3" -2500
xmark "2" -1500
xmark "1" -500
ymark "A" 975
ymark "B" 2175
ymark "C" 3300
ymark "D" 4475
pagenumber (-375,50)
{schrep "basenets" (1,20)(2,35)(3,25)}
schrep "basenets" (1,20)(3,25)
schrep "netsbypage" (1,7)(2,15)(3,20)(4,15)(5,21)
schrep "synonyms" (1,15)(2,20)(3,25)(4,21)
{schrep "crefparts" (1,10)(2,20)(3,50)}
schrep "crefparts" (1,10)(2,20)(3,20)

pagename "BPAGE_CONFIDENTIAL"
lowerleft(-7800,225)
upperright(-125,4825)
xmark "8" -7500
xmark "7" -6500
xmark "6" -5500
xmark "5" -4500
xmark "4" -3500
xmark "3" -2500
xmark "2" -1500
xmark "1" -500
ymark "A" 975
ymark "B" 2175
ymark "C" 3300
ymark "D" 4475
{schrep "basenets" (1,20)(2,35)(3,25)}
schrep "basenets" (1,20)(3,25)
schrep "netsbypage" (1,7)(2,15)(3,20)(4,15)(5,21)
schrep "synonyms" (1,15)(2,20)(3,25)(4,21)
{schrep "crefparts" (1,10)(2,20)(3,50)}
schrep "crefparts" (1,10)(2,20)(3,20)

pagename "BPAGE_MR266"
lowerleft(-7800,225)
upperright(-125,4825)
xmark "8" -7500
xmark "7" -6500
xmark "6" -5500
xmark "5" -4500
xmark "4" -3500
xmark "3" -2500
xmark "2" -1500
xmark "1" -500
ymark "A" 975
ymark "B" 2175
ymark "C" 3300
ymark "D" 4475
{schrep "basenets" (1,20)(2,35)(3,25)}
schrep "basenets" (1,20)(3,25)
schrep "netsbypage" (1,7)(2,15)(3,20)(4,15)(5,21)
schrep "synonyms" (1,15)(2,20)(3,25)(4,21)
{schrep "crefparts" (1,10)(2,20)(3,50)}
schrep "crefparts" (1,10)(2,20)(3,20)

pagename "BPAGE_PCG"
lowerleft(-7800,225)
upperright(-125,4825)
xmark "8" -7500
xmark "7" -6500
xmark "6" -5500
xmark "5" -4500
xmark "4" -3500
xmark "3" -2500
xmark "2" -1500
xmark "1" -500
ymark "A" 975
ymark "B" 2175
ymark "C" 3300
ymark "D" 4475
{schrep "basenets" (1,20)(2,35)(3,25)}
schrep "basenets" (1,20)(3,25)
schrep "netsbypage" (1,7)(2,15)(3,20)(4,15)(5,21)
schrep "synonyms" (1,15)(2,20)(3,25)(4,21)
{schrep "crefparts" (1,10)(2,20)(3,50)}
schrep "crefparts" (1,10)(2,20)(3,20)

pagename "BPAGE_PF400"
lowerleft(-7800,225)
upperright(-125,4825)
xmark "8" -7500
xmark "7" -6500
xmark "6" -5500
xmark "5" -4500
xmark "4" -3500
xmark "3" -2500
xmark "2" -1500
xmark "1" -500
ymark "A" 975
ymark "B" 2175
ymark "C" 3300
ymark "D" 4475
{schrep "basenets" (1,20)(2,35)(3,25)}
schrep "basenets" (1,20)(3,25)
schrep "netsbypage" (1,7)(2,15)(3,20)(4,15)(5,21)
schrep "synonyms" (1,15)(2,20)(3,25)(4,21)
{schrep "crefparts" (1,10)(2,20)(3,50)}
schrep "crefparts" (1,10)(2,20)(3,20)

pagename "BPAGE_R_SECRET"
lowerleft(-7800,225)
upperright(-125,4825)
xmark "8" -7500
xmark "7" -6500
xmark "6" -5500
xmark "5" -4500
xmark "4" -3500
xmark "3" -2500
xmark "2" -1500
xmark "1" -500
ymark "A" 975
ymark "B" 2175
ymark "C" 3300
ymark "D" 4475
{schrep "basenets" (1,20)(2,35)(3,25)}
schrep "basenets" (1,20)(3,25)
schrep "netsbypage" (1,7)(2,15)(3,20)(4,15)(5,21)
schrep "synonyms" (1,15)(2,20)(3,25)(4,21)
{schrep "crefparts" (1,10)(2,20)(3,50)}
schrep "crefparts" (1,10)(2,20)(3,20)

pagename "BPAGE_SECRET"
lowerleft(-7800,225)
upperright(-125,4825)
xmark "8" -7500
xmark "7" -6500
xmark "6" -5500
xmark "5" -4500
xmark "4" -3500
xmark "3" -2500
xmark "2" -1500
xmark "1" -500
ymark "A" 975
ymark "B" 2175
ymark "C" 3300
ymark "D" 4475
{schrep "basenets" (1,20)(2,35)(3,25)}
schrep "basenets" (1,20)(3,25)
schrep "netsbypage" (1,7)(2,15)(3,20)(4,15)(5,21)
schrep "synonyms" (1,15)(2,20)(3,25)(4,21)
{schrep "crefparts" (1,10)(2,20)(3,50)}
schrep "crefparts" (1,10)(2,20)(3,20)

pagename "BPAGE_SRP"
lowerleft(-7800,225)
upperright(-125,4825)
xmark "8" -7500
xmark "7" -6500
xmark "6" -5500
xmark "5" -4500
xmark "4" -3500
xmark "3" -2500
xmark "2" -1500
xmark "1" -500
ymark "A" 975
ymark "B" 2175
ymark "C" 3300
ymark "D" 4475
{schrep "basenets" (1,20)(2,35)(3,25)}
schrep "basenets" (1,20)(3,25)
schrep "netsbypage" (1,7)(2,15)(3,20)(4,15)(5,21)
schrep "synonyms" (1,15)(2,20)(3,25)(4,21)
{schrep "crefparts" (1,10)(2,20)(3,50)}
schrep "crefparts" (1,10)(2,20)(3,20)

pagename "BPAGE_TOPSECRET"
lowerleft(-7800,225)
upperright(-125,4825)
xmark "8" -7500
xmark "7" -6500
xmark "6" -5500
xmark "5" -4500
xmark "4" -3500
xmark "3" -2500
xmark "2" -1500
xmark "1" -500
ymark "A" 975
ymark "B" 2175
ymark "C" 3300
ymark "D" 4475
{schrep "basenets" (1,20)(2,35)(3,25)}
schrep "basenets" (1,20)(3,25)
schrep "netsbypage" (1,7)(2,15)(3,20)(4,15)(5,21)
schrep "synonyms" (1,15)(2,20)(3,25)(4,21)
{schrep "crefparts" (1,10)(2,20)(3,50)}
schrep "crefparts" (1,10)(2,20)(3,20)

pagename "BPAGE_WS400"
lowerleft(-7800,225)
upperright(-125,4825)
xmark "8" -7500
xmark "7" -6500
xmark "6" -5500
xmark "5" -4500
xmark "4" -3500
xmark "3" -2500
xmark "2" -1500
xmark "1" -500
ymark "A" 975
ymark "B" 2175
ymark "C" 3300
ymark "D" 4475
{schrep "basenets" (1,20)(2,35)(3,25)}
schrep "basenets" (1,20)(3,25)
schrep "netsbypage" (1,7)(2,15)(3,20)(4,15)(5,21)
schrep "synonyms" (1,15)(2,20)(3,25)(4,21)
{schrep "crefparts" (1,10)(2,20)(3,50)}
schrep "crefparts" (1,10)(2,20)(3,20)

pagename "INTELBPAGE"
lowerleft(-7800,225)
upperright(-125,4825)
xmark "8" -7500
xmark "7" -6500
xmark "6" -5500
xmark "5" -4500
xmark "4" -3500
xmark "3" -2500
xmark "2" -1500
xmark "1" -500
ymark "A" 975
ymark "B" 2175
ymark "C" 3300
ymark "D" 4475
{schrep "basenets" (1,20)(2,35)(3,25)}
schrep "basenets" (1,20)(3,25)
schrep "netsbypage" (1,7)(2,15)(3,20)(4,15)(5,21)
schrep "synonyms" (1,15)(2,20)(3,25)(4,21)
{schrep "crefparts" (1,10)(2,20)(3,50)}
schrep "crefparts" (1,10)(2,20)(3,20)
pagename "BPAGE_DUP"
lowerleft(-7800,225)
upperright(-125,4825)
xmark "8" -7500
xmark "7" -6500
xmark "6" -5500
xmark "5" -4500
xmark "4" -3500
xmark "3" -2500
xmark "2" -1500
xmark "1" -500
ymark "A" 975
ymark "B" 2175
ymark "C" 3300
ymark "D" 4475
{schrep "basenets" (1,20)(2,35)(3,25)}
{schrep "basenets" (1,20)(3,21)}
schrep "basenets" (1,20)(3,8)
{schrep "netsbypage" (1,7)(2,15)(3,20)(4,15)(5,21)}
schrep "netsbypage" (1,5)(2,20)(5,21)
schrep "synonyms" (1,15)(2,20)(3,25)(4,21)
{schrep "crefparts" (1,10)(2,20)(3,50)}
schrep "crefparts" (1,7)(2,20)(3,10)

pagename "bpage_esd"
version 1
lowerleft(-7800,225)
upperright(-125,4825)
xmark "8" -7500
xmark "7" -6500
xmark "6" -5500
xmark "5" -4500
xmark "4" -3500
xmark "3" -2500
xmark "2" -1500
xmark "1" -500
ymark "A" 975
ymark "B" 2175
ymark "C" 3300
ymark "D" 4475
pagename "bpage_esd"
version 2
lowerleft(-7800,225)
upperright(-125,4825)
xmark "8" -7500
xmark "7" -6500
xmark "6" -5500
xmark "5" -4500
xmark "4" -3500
xmark "3" -2500
xmark "2" -1500
xmark "1" -500
ymark "A" 975
ymark "B" 2175
ymark "C" 3300
ymark "D" 4475
pagename "bpage_esd"
version 3
lowerleft (-8000, 0)
upperright (0, 5000)
xmark "1" -1000
xmark "2" -3000
xmark "3" -5000
xmark "4" -7000
ymark "A" 1250
ymark "B" 3750
excludearea "1" (-8000,0) (0,400)
{schrep "basenets" (1,20)(2,35)(3,25)}
schrep "basenets" (1,20)(3,21)
{schrep "netsbypage" (1,7)(2,15)(3,20)(4,15)(5,21)}
schrep "netsbypage" (1,5)(2,20)(5,21)
schrep "synonyms" (1,15)(2,20)(3,25)(4,21)
{schrep "crefparts" (1,10)(2,20)(3,50)}
schrep "crefparts" (1,7)(2,20)(3,20)


pagename "bpluspage_jic"
version 1
lowerleft(-11000,200)
upperright(0,7300)
xmark "8" -11000
xmark "7" -9625
xmark "6" -8250
xmark "5" -6875
xmark "4" -5500
xmark "3" -4125
xmark "2" -2725
xmark "1" -1375
ymark "A" 1825
ymark "B" 3675
ymark "C" 5475
ymark "D" 7300
pagename "bpluspage_jic"
version 2
lowerleft(-11000,200)
upperright(0,7300)
xmark "8" -11000
xmark "7" -9625
xmark "6" -8250
xmark "5" -6875
xmark "4" -5500
xmark "3" -4125
xmark "2" -2725
xmark "1" -1375
ymark "A" 1825
ymark "B" 3675
ymark "C" 5475
ymark "D" 7300

BIFLAG "FLAG" VERSION 9
BIFLAG "FLAG" VERSION 10
BIFLAG "FLAG" VERSION 11
BIFLAG "FLAG" VERSION 12
BIFLAG "IOPORT" VERSION 1
BIFLAG "OFFPAGE" VERSION 3
BIFLAG "OFFPAGE" VERSION 6
BIFLAG "OFFPAGE_BI" VERSION 1
BIFLAG "OFFPAGE_IN" VERSION 1
BIFLAG "OFFPAGE_OUT" VERSION 1
INFLAG "FLAG" VERSION 1
INFLAG "FLAG" VERSION 2
INFLAG "FLAG" VERSION 3
INFLAG "FLAG" VERSION 4
INFLAG "INPORT" VERSION 1
INFLAG "OFFPAGE" VERSION 1
INFLAG "OFFPAGE" VERSION 1
INFLAG "OFFPAGE" VERSION 4
OUTFLAG "FLAG" VERSION 5
OUTFLAG "FLAG" VERSION 6
OUTFLAG "FLAG" VERSION 7
OUTFLAG "FLAG" VERSION 8
OUTFLAG "OFFPAGE" VERSION 2
OUTFLAG "OFFPAGE" VERSION 5
OUTFLAG "OUTPORT" VERSION 1
BIFLAG "OFFPAG_BI" VERSION 1
BIFLAG "OFFPAG_IN" VERSION 1
BIFLAG "OFFPAG_OUT" VERSION 1
